(kicad_pcb
	(version 20260206)
	(generator "pcbnew")
	(generator_version "10.0")
	(general
		(thickness 1.6)
		(legacy_teardrops no)
	)
	(paper "A4")
	(title_block
		(title "peb — Lightning_PEB_BRD.brd")
		(comment 1 "Lightning (Wiwynn / Facebook NVMe JBOF) / footprints 988-996 of 2563")
	)
	(layers
		(0 "F.Cu" signal "TOP")
		(4 "In1.Cu" signal "L2GND")
		(6 "In2.Cu" signal "L3")
		(8 "In3.Cu" signal "L4VCC")
		(10 "In4.Cu" signal "L5VCC")
		(12 "In5.Cu" signal "L6")
		(14 "In6.Cu" signal "L7GND")
		(2 "B.Cu" signal "BOTTOM")
		(9 "F.Adhes" user "F.Adhesive")
		(11 "B.Adhes" user "B.Adhesive")
		(13 "F.Paste" user "Package Geometry/Pastemask Top")
		(15 "B.Paste" user "Package Geometry/Pastemask Bottom")
		(5 "F.SilkS" user "Ref Des/Silkscreen Top")
		(7 "B.SilkS" user "Ref Des/Silkscreen Bottom")
		(1 "F.Mask" user "Board Geometry/Soldermask Top")
		(3 "B.Mask" user "Board Geometry/Soldermask Bottom")
		(17 "Dwgs.User" user "User.Drawings")
		(19 "Cmts.User" user "User.Comments")
		(21 "Eco1.User" user "User.Eco1")
		(23 "Eco2.User" user "User.Eco2")
		(25 "Edge.Cuts" user "Board Geometry/Outline")
		(27 "Margin" user)
		(31 "F.CrtYd" user "Package Geometry/Place Bound Top")
		(29 "B.CrtYd" user "Package Geometry/Place Bound Bottom")
		(35 "F.Fab" user "Ref Des/Assembly Top")
		(33 "B.Fab" user "Ref Des/Assembly Bottom")
	)
	(footprint ""
		(layer "F.Cu")
		(at 68.3514 -120.9802)
		(property "Reference" "U23"
			(at 0 0 0)
			(layer "F.SilkS")
			(hide yes)
			(effects
				(font
					(size 1.27 1.27)
				)
			)
		)
		(property "Value" "2N7002DW-7F-GP"
			(at -2.3622 -8.2042 0)
			(unlocked yes)
			(layer "F.Fab")
			(hide yes)
			(effects
				(font
					(size 1.016 1.016)
					(thickness 0.1524)
				)
			)
		)
		(property "Device Type" "SOT-363H44"
			(at -2.3622 -10.1092 0)
			(unlocked yes)
			(layer "F.Fab")
			(hide yes)
			(effects
				(font
					(size 1.016 1.016)
					(thickness 0.1524)
				)
			)
		)
		(duplicate_pad_numbers_are_jumpers no)
		(fp_line
			(start -1.4478 -1.7018)
			(end -1.4478 1.7018)
			(stroke
				(width 0.1524)
				(type default)
			)
			(layer "F.SilkS")
		)
		(fp_line
			(start -1.4478 1.7018)
			(end 1.4478 1.7018)
			(stroke
				(width 0.1524)
				(type default)
			)
			(layer "F.SilkS")
		)
		(fp_line
			(start -1.27 1.524)
			(end -1.27 0.6604)
			(stroke
				(width 0.4826)
				(type default)
			)
			(layer "F.SilkS")
		)
		(fp_line
			(start 1.4478 -1.7018)
			(end -1.4478 -1.7018)
			(stroke
				(width 0.1524)
				(type default)
			)
			(layer "F.SilkS")
		)
		(fp_line
			(start 1.4478 1.7018)
			(end 1.4478 -1.7018)
			(stroke
				(width 0.1524)
				(type default)
			)
			(layer "F.SilkS")
		)
		(fp_poly
			(pts
				(xy -1.524 -1.778) (xy 1.524 -1.778) (xy 1.524 1.778) (xy -1.524 1.778)
			)
			(stroke
				(width 0)
				(type default)
			)
			(fill no)
			(layer "F.CrtYd")
		)
		(fp_poly
			(pts
				(xy -1.524 -1.778) (xy 1.524 -1.778) (xy 1.524 1.778) (xy -1.524 1.778)
			)
			(stroke
				(width 0)
				(type default)
			)
			(fill no)
			(layer "F.Fab")
		)
		(pad "1" smd rect
			(at -0.65024 0.9398)
			(size 0.4064 1.016)
			(layers "F.Cu" "F.Mask" "F.Paste")
			(net "BMC_I2C4_MINI4_SCL_S")
		)
		(pad "2" smd rect
			(at 0 0.9398)
			(size 0.4064 1.016)
			(layers "F.Cu" "F.Mask" "F.Paste")
			(net "I2C4_LS_G2")
		)
		(pad "3" smd rect
			(at 0.65024 0.9398)
			(size 0.4064 1.016)
			(layers "F.Cu" "F.Mask" "F.Paste")
			(net "BMC_I2C4_MINI4_SDA")
		)
		(pad "4" smd rect
			(at 0.65024 -0.9398)
			(size 0.4064 1.016)
			(layers "F.Cu" "F.Mask" "F.Paste")
			(net "BMC_I2C4_MINI4_SDA_S")
		)
		(pad "5" smd rect
			(at 0 -0.9398)
			(size 0.4064 1.016)
			(layers "F.Cu" "F.Mask" "F.Paste")
			(net "I2C4_LS_G1")
		)
		(pad "6" smd rect
			(at -0.65024 -0.9398)
			(size 0.4064 1.016)
			(layers "F.Cu" "F.Mask" "F.Paste")
			(net "BMC_I2C4_MINI4_SCL")
		)
	)
	(footprint ""
		(layer "F.Cu")
		(at 181.61 -23.622 -90)
		(property "Reference" "C408"
			(at 0 0 270)
			(layer "F.SilkS")
			(hide yes)
			(effects
				(font
					(size 1.27 1.27)
				)
			)
		)
		(property "Value" "SCD22U10V2KX-1GP"
			(at 1.1811 -2.7051 270)
			(unlocked yes)
			(layer "F.Fab")
			(hide yes)
			(effects
				(font
					(size 1.016 1.016)
					(thickness 0.1524)
				)
			)
		)
		(property "Device Type" "C402H22"
			(at 1.1811 -4.2291 270)
			(unlocked yes)
			(layer "F.Fab")
			(hide yes)
			(effects
				(font
					(size 1.016 1.016)
					(thickness 0.1524)
				)
			)
		)
		(duplicate_pad_numbers_are_jumpers no)
		(fp_rect
			(start -0.4318 0.9525)
			(end 0.4318 -0.9525)
			(stroke
				(width 0)
				(type default)
			)
			(fill no)
			(layer "F.CrtYd")
		)
		(fp_rect
			(start -0.4318 0.9525)
			(end 0.4318 -0.9525)
			(stroke
				(width 0)
				(type default)
			)
			(fill no)
			(layer "F.Fab")
		)
		(pad "1" smd custom
			(at 0 -0.4445 270)
			(size 0.1524 0.1524)
			(layers "F.Cu" "F.Mask" "F.Paste")
			(net "PCIE_TX_CAP_N94")
			(options
				(clearance outline)
				(anchor circle)
			)
			(primitives
				(gr_poly
					(pts
						(arc
							(start 0.3048 -0.2032)
							(mid 0.275042 -0.275042)
							(end 0.2032 -0.3048)
						)
						(arc
							(start -0.2032 -0.3048)
							(mid -0.275042 -0.275042)
							(end -0.3048 -0.2032)
						)
						(arc
							(start -0.3048 0.2032)
							(mid -0.275042 0.275042)
							(end -0.2032 0.3048)
						)
						(arc
							(start 0.2032 0.3048)
							(mid 0.275042 0.275042)
							(end 0.3048 0.2032)
						)
					)
					(width 0)
					(fill yes)
				)
			)
		)
		(pad "2" smd custom
			(at 0 0.4445 270)
			(size 0.1524 0.1524)
			(layers "F.Cu" "F.Mask" "F.Paste")
			(net "PCIE_TX_N94")
			(options
				(clearance outline)
				(anchor circle)
			)
			(primitives
				(gr_poly
					(pts
						(arc
							(start 0.3048 -0.2032)
							(mid 0.275042 -0.275042)
							(end 0.2032 -0.3048)
						)
						(arc
							(start -0.2032 -0.3048)
							(mid -0.275042 -0.275042)
							(end -0.3048 -0.2032)
						)
						(arc
							(start -0.3048 0.2032)
							(mid -0.275042 0.275042)
							(end -0.2032 0.3048)
						)
						(arc
							(start 0.2032 0.3048)
							(mid 0.275042 0.275042)
							(end 0.3048 0.2032)
						)
					)
					(width 0)
					(fill yes)
				)
			)
		)
	)
	(footprint ""
		(layer "F.Cu")
		(at 11.4046 -52.0446 90)
		(property "Reference" "D14"
			(at 0 0 90)
			(layer "F.SilkS")
			(hide yes)
			(effects
				(font
					(size 1.27 1.27)
				)
			)
		)
		(property "Value" "PGB1010603MR-GP"
			(at -0.0254 -2.8956 90)
			(unlocked yes)
			(layer "F.Fab")
			(hide yes)
			(effects
				(font
					(size 1.016 1.016)
					(thickness 0.1524)
				)
			)
		)
		(property "Device Type" "L1608-UH15"
			(at -0.0254 -4.4196 90)
			(unlocked yes)
			(layer "F.Fab")
			(hide yes)
			(effects
				(font
					(size 1.016 1.016)
					(thickness 0.1524)
				)
			)
		)
		(duplicate_pad_numbers_are_jumpers no)
		(fp_line
			(start 0.254 0)
			(end -0.254 0)
			(stroke
				(width 0.2032)
				(type default)
			)
			(layer "F.SilkS")
		)
		(fp_rect
			(start -0.5842 1.3335)
			(end 0.5842 -1.3335)
			(stroke
				(width 0)
				(type default)
			)
			(fill no)
			(layer "F.CrtYd")
		)
		(fp_rect
			(start -0.5842 1.3335)
			(end 0.5842 -1.3335)
			(stroke
				(width 0)
				(type default)
			)
			(fill no)
			(layer "F.Fab")
		)
		(pad "1" smd custom
			(at 0 -0.762 90)
			(size 0.2159 0.2159)
			(layers "F.Cu" "F.Mask" "F.Paste")
			(net "NIC0_MDI0_N0_R")
			(options
				(clearance outline)
				(anchor circle)
			)
			(primitives
				(gr_poly
					(pts
						(arc
							(start -0.3302 -0.4318)
							(mid -0.402042 -0.402042)
							(end -0.4318 -0.3302)
						)
						(arc
							(start -0.4318 0.3302)
							(mid -0.402042 0.402042)
							(end -0.3302 0.4318)
						)
						(arc
							(start 0.3302 0.4318)
							(mid 0.402042 0.402042)
							(end 0.4318 0.3302)
						)
						(arc
							(start 0.4318 -0.3302)
							(mid 0.402042 -0.402042)
							(end 0.3302 -0.4318)
						)
					)
					(width 0)
					(fill yes)
				)
			)
		)
		(pad "2" smd custom
			(at 0 0.762 90)
			(size 0.2159 0.2159)
			(layers "F.Cu" "F.Mask" "F.Paste")
			(net "GND")
			(options
				(clearance outline)
				(anchor circle)
			)
			(primitives
				(gr_poly
					(pts
						(arc
							(start -0.3302 -0.4318)
							(mid -0.402042 -0.402042)
							(end -0.4318 -0.3302)
						)
						(arc
							(start -0.4318 0.3302)
							(mid -0.402042 0.402042)
							(end -0.3302 0.4318)
						)
						(arc
							(start 0.3302 0.4318)
							(mid 0.402042 0.402042)
							(end 0.4318 0.3302)
						)
						(arc
							(start 0.4318 -0.3302)
							(mid 0.402042 -0.402042)
							(end 0.3302 -0.4318)
						)
					)
					(width 0)
					(fill yes)
				)
			)
		)
	)
	(footprint ""
		(layer "F.Cu")
		(at 60.8584 -37.5666 180)
		(property "Reference" "PC29"
			(at 0 0 180)
			(layer "F.SilkS")
			(hide yes)
			(effects
				(font
					(size 1.27 1.27)
				)
			)
		)
		(property "Value" "SC1U10V2KX-4-GP"
			(at 1.1811 -2.7051 180)
			(unlocked yes)
			(layer "F.Fab")
			(hide yes)
			(effects
				(font
					(size 1.016 1.016)
					(thickness 0.1524)
				)
			)
		)
		(property "Device Type" "C402H22"
			(at 1.1811 -4.2291 180)
			(unlocked yes)
			(layer "F.Fab")
			(hide yes)
			(effects
				(font
					(size 1.016 1.016)
					(thickness 0.1524)
				)
			)
		)
		(duplicate_pad_numbers_are_jumpers no)
		(fp_rect
			(start -0.4318 0.9525)
			(end 0.4318 -0.9525)
			(stroke
				(width 0)
				(type default)
			)
			(fill no)
			(layer "F.CrtYd")
		)
		(fp_rect
			(start -0.4318 0.9525)
			(end 0.4318 -0.9525)
			(stroke
				(width 0)
				(type default)
			)
			(fill no)
			(layer "F.Fab")
		)
		(pad "1" smd custom
			(at 0 -0.4445 180)
			(size 0.1524 0.1524)
			(layers "F.Cu" "F.Mask" "F.Paste")
			(net "GND")
			(options
				(clearance outline)
				(anchor circle)
			)
			(primitives
				(gr_poly
					(pts
						(arc
							(start 0.3048 -0.2032)
							(mid 0.275042 -0.275042)
							(end 0.2032 -0.3048)
						)
						(arc
							(start -0.2032 -0.3048)
							(mid -0.275042 -0.275042)
							(end -0.3048 -0.2032)
						)
						(arc
							(start -0.3048 0.2032)
							(mid -0.275042 0.275042)
							(end -0.2032 0.3048)
						)
						(arc
							(start 0.2032 0.3048)
							(mid 0.275042 0.275042)
							(end 0.3048 0.2032)
						)
					)
					(width 0)
					(fill yes)
				)
			)
		)
		(pad "2" smd custom
			(at 0 0.4445 180)
			(size 0.1524 0.1524)
			(layers "F.Cu" "F.Mask" "F.Paste")
			(net "P3V3_STBY_VREG")
			(options
				(clearance outline)
				(anchor circle)
			)
			(primitives
				(gr_poly
					(pts
						(arc
							(start 0.3048 -0.2032)
							(mid 0.275042 -0.275042)
							(end 0.2032 -0.3048)
						)
						(arc
							(start -0.2032 -0.3048)
							(mid -0.275042 -0.275042)
							(end -0.3048 -0.2032)
						)
						(arc
							(start -0.3048 0.2032)
							(mid -0.275042 0.275042)
							(end -0.2032 0.3048)
						)
						(arc
							(start 0.2032 0.3048)
							(mid 0.275042 0.275042)
							(end 0.3048 0.2032)
						)
					)
					(width 0)
					(fill yes)
				)
			)
		)
	)
	(footprint ""
		(layer "F.Cu")
		(at 327.914 -74.93 90)
		(property "Reference" "R2"
			(at 0 0 90)
			(layer "F.SilkS")
			(hide yes)
			(effects
				(font
					(size 1.27 1.27)
				)
			)
		)
		(property "Value" "20KR2F-L-GP"
			(at 0.064008 -3.993896 90)
			(unlocked yes)
			(layer "F.Fab")
			(hide yes)
			(effects
				(font
					(size 1.016 1.016)
					(thickness 0.1524)
				)
			)
		)
		(property "Device Type" "R402H16"
			(at 0.064008 -5.517896 90)
			(unlocked yes)
			(layer "F.Fab")
			(hide yes)
			(effects
				(font
					(size 1.016 1.016)
					(thickness 0.1524)
				)
			)
		)
		(duplicate_pad_numbers_are_jumpers no)
		(fp_line
			(start 0.508 -0.9398)
			(end -0.508 -0.9398)
			(stroke
				(width 0.1524)
				(type default)
			)
			(layer "F.SilkS")
		)
		(fp_line
			(start -0.508 -0.9398)
			(end -0.508 0.9398)
			(stroke
				(width 0.1524)
				(type default)
			)
			(layer "F.SilkS")
		)
		(fp_rect
			(start -0.508 0.9398)
			(end 0.508 -0.9398)
			(stroke
				(width 0)
				(type default)
			)
			(fill no)
			(layer "F.CrtYd")
		)
		(fp_rect
			(start -0.508 0.9398)
			(end 0.508 -0.9398)
			(stroke
				(width 0)
				(type default)
			)
			(fill no)
			(layer "F.Fab")
		)
		(pad "1" smd custom
			(at 0 -0.4445 90)
			(size 0.1397 0.1397)
			(layers "F.Cu" "F.Mask" "F.Paste")
			(net "DUT_VDDO")
			(options
				(clearance outline)
				(anchor circle)
			)
			(primitives
				(gr_poly
					(pts
						(arc
							(start -0.1778 -0.2794)
							(mid -0.249642 -0.249642)
							(end -0.2794 -0.1778)
						)
						(arc
							(start -0.2794 0.1778)
							(mid -0.249642 0.249642)
							(end -0.1778 0.2794)
						)
						(arc
							(start 0.1778 0.2794)
							(mid 0.249642 0.249642)
							(end 0.2794 0.1778)
						)
						(arc
							(start 0.2794 -0.1778)
							(mid 0.249642 -0.249642)
							(end 0.1778 -0.2794)
						)
					)
					(width 0)
					(fill yes)
				)
			)
		)
		(pad "2" smd custom
			(at 0 0.4445 90)
			(size 0.1397 0.1397)
			(layers "F.Cu" "F.Mask" "F.Paste")
			(net "AVS_ENB2_R")
			(options
				(clearance outline)
				(anchor circle)
			)
			(primitives
				(gr_poly
					(pts
						(arc
							(start -0.1778 -0.2794)
							(mid -0.249642 -0.249642)
							(end -0.2794 -0.1778)
						)
						(arc
							(start -0.2794 0.1778)
							(mid -0.249642 0.249642)
							(end -0.1778 0.2794)
						)
						(arc
							(start 0.1778 0.2794)
							(mid 0.249642 0.249642)
							(end 0.2794 0.1778)
						)
						(arc
							(start 0.2794 -0.1778)
							(mid 0.249642 -0.249642)
							(end 0.1778 -0.2794)
						)
					)
					(width 0)
					(fill yes)
				)
			)
		)
	)
	(footprint ""
		(layer "F.Cu")
		(at 310.007 -64.7446)
		(property "Reference" "PG57"
			(at 0 0 0)
			(layer "F.SilkS")
			(hide yes)
			(effects
				(font
					(size 1.27 1.27)
				)
			)
		)
		(property "Value" "GAP-CLOSE-PWR-3-GP"
			(at 0.0254 -6.5786 0)
			(unlocked yes)
			(layer "F.Fab")
			(hide yes)
			(effects
				(font
					(size 1.016 1.016)
					(thickness 0.1524)
				)
			)
		)
		(property "Device Type" "GAP-CLOSE-PWR-3"
			(at 0.0254 -8.255 0)
			(unlocked yes)
			(layer "F.Fab")
			(hide yes)
			(effects
				(font
					(size 1.016 1.016)
					(thickness 0.1524)
				)
			)
		)
		(duplicate_pad_numbers_are_jumpers no)
		(fp_rect
			(start -0.7112 0.4572)
			(end 0.7112 -0.4572)
			(stroke
				(width 0)
				(type default)
			)
			(fill no)
			(layer "F.CrtYd")
		)
		(fp_poly
			(pts
				(xy -0.7112 -0.4572) (xy 0.7112 -0.4572) (xy 0.7112 0.4572) (xy -0.7112 0.4572)
			)
			(stroke
				(width 0)
				(type default)
			)
			(fill no)
			(layer "F.Fab")
		)
		(pad "1" smd rect
			(at -0.3048 0)
			(size 0.6604 0.762)
			(layers "F.Cu" "F.Mask" "F.Paste")
			(net "DUT_VDD")
		)
		(pad "2" smd rect
			(at 0.3048 0)
			(size 0.6604 0.762)
			(layers "F.Cu" "F.Mask" "F.Paste")
			(net "P0V9_E")
		)
	)
	(footprint ""
		(layer "F.Cu")
		(at 335.153 -185.801)
		(property "Reference" "TP167"
			(at 0 0 0)
			(layer "F.SilkS")
			(hide yes)
			(effects
				(font
					(size 1.27 1.27)
				)
			)
		)
		(property "Value" "TPAD28-2-GP"
			(at -0.0127 -1.6637 0)
			(unlocked yes)
			(layer "F.Fab")
			(hide yes)
			(effects
				(font
					(size 1.016 1.016)
					(thickness 0.1524)
				)
			)
		)
		(property "Device Type" "TPAD28"
			(at -0.0127 -3.1877 0)
			(unlocked yes)
			(layer "F.Fab")
			(hide yes)
			(effects
				(font
					(size 1.016 1.016)
					(thickness 0.1524)
				)
			)
		)
		(duplicate_pad_numbers_are_jumpers no)
		(fp_poly
			(pts
				(arc
					(start 0.3556 0)
					(mid -0.3556 0)
					(end 0.3556 0)
				)
			)
			(stroke
				(width 0)
				(type default)
			)
			(fill no)
			(layer "F.CrtYd")
		)
		(fp_poly
			(pts
				(arc
					(start 0.6096 0)
					(mid -0.6096 0)
					(end 0.6096 0)
				)
			)
			(stroke
				(width 0)
				(type default)
			)
			(fill no)
			(layer "F.Fab")
		)
		(pad "1" smd circle
			(at 0 0)
			(size 0.7112 0.7112)
			(layers "F.Cu" "F.Mask" "F.Paste")
			(net "IOEXP4_GPIO13")
		)
	)
	(footprint ""
		(layer "F.Cu")
		(at 71.686166 -90.07856 -90)
		(property "Reference" "R479"
			(at 0 0 270)
			(layer "F.SilkS")
			(hide yes)
			(effects
				(font
					(size 1.27 1.27)
				)
			)
		)
		(property "Value" "51R2010F-GP"
			(at 0.254 -8.0772 270)
			(unlocked yes)
			(layer "F.Fab")
			(hide yes)
			(effects
				(font
					(size 1.016 1.016)
					(thickness 0.1524)
				)
			)
		)
		(property "Device Type" "R2010H28"
			(at 0.254 -9.6774 270)
			(unlocked yes)
			(layer "F.Fab")
			(hide yes)
			(effects
				(font
					(size 1.016 1.016)
					(thickness 0.1524)
				)
			)
		)
		(duplicate_pad_numbers_are_jumpers no)
		(fp_line
			(start -1.651 3.302)
			(end 1.651 3.302)
			(stroke
				(width 0.1524)
				(type default)
			)
			(layer "F.SilkS")
		)
		(fp_line
			(start 1.651 3.302)
			(end 1.651 -3.302)
			(stroke
				(width 0.1524)
				(type default)
			)
			(layer "F.SilkS")
		)
		(fp_line
			(start -1.651 -3.302)
			(end -1.651 3.302)
			(stroke
				(width 0.1524)
				(type default)
			)
			(layer "F.SilkS")
		)
		(fp_line
			(start 1.651 -3.302)
			(end -1.651 -3.302)
			(stroke
				(width 0.1524)
				(type default)
			)
			(layer "F.SilkS")
		)
		(fp_rect
			(start -1.7272 -3.3782)
			(end 1.7272 3.3782)
			(stroke
				(width 0)
				(type default)
			)
			(fill no)
			(layer "F.CrtYd")
		)
		(fp_poly
			(pts
				(xy 1.7272 3.3782) (xy 1.7272 -3.3782) (xy -1.7272 -3.3782) (xy -1.7272 3.3782)
			)
			(stroke
				(width 0)
				(type default)
			)
			(fill no)
			(layer "F.Fab")
		)
		(pad "1" smd rect
			(at 0 -2.3495 270)
			(size 2.794 1.143)
			(layers "F.Cu" "F.Mask" "F.Paste")
			(net "P3V3_STBY")
		)
		(pad "2" smd rect
			(at 0 2.3495 270)
			(size 2.794 1.143)
			(layers "F.Cu" "F.Mask" "F.Paste")
			(net "HB_OUT")
		)
	)
	(footprint ""
		(layer "F.Cu")
		(at 121.5136 -17.0688 180)
		(property "Reference" "R751"
			(at 0 0 180)
			(layer "F.SilkS")
			(hide yes)
			(effects
				(font
					(size 1.27 1.27)
				)
			)
		)
		(property "Value" "4K7R2F-GP"
			(at 0.064008 -3.993896 180)
			(unlocked yes)
			(layer "F.Fab")
			(hide yes)
			(effects
				(font
					(size 1.016 1.016)
					(thickness 0.1524)
				)
			)
		)
		(property "Device Type" "R402H16"
			(at 0.064008 -5.517896 180)
			(unlocked yes)
			(layer "F.Fab")
			(hide yes)
			(effects
				(font
					(size 1.016 1.016)
					(thickness 0.1524)
				)
			)
		)
		(duplicate_pad_numbers_are_jumpers no)
		(fp_line
			(start 0.508 -0.9398)
			(end -0.508 -0.9398)
			(stroke
				(width 0.1524)
				(type default)
			)
			(layer "F.SilkS")
		)
		(fp_line
			(start -0.508 -0.9398)
			(end -0.508 0.9398)
			(stroke
				(width 0.1524)
				(type default)
			)
			(layer "F.SilkS")
		)
		(fp_rect
			(start -0.508 0.9398)
			(end 0.508 -0.9398)
			(stroke
				(width 0)
				(type default)
			)
			(fill no)
			(layer "F.CrtYd")
		)
		(fp_rect
			(start -0.508 0.9398)
			(end 0.508 -0.9398)
			(stroke
				(width 0)
				(type default)
			)
			(fill no)
			(layer "F.Fab")
		)
		(pad "1" smd custom
			(at 0 -0.4445 180)
			(size 0.1397 0.1397)
			(layers "F.Cu" "F.Mask" "F.Paste")
			(net "GND")
			(options
				(clearance outline)
				(anchor circle)
			)
			(primitives
				(gr_poly
					(pts
						(arc
							(start -0.1778 -0.2794)
							(mid -0.249642 -0.249642)
							(end -0.2794 -0.1778)
						)
						(arc
							(start -0.2794 0.1778)
							(mid -0.249642 0.249642)
							(end -0.1778 0.2794)
						)
						(arc
							(start 0.1778 0.2794)
							(mid 0.249642 0.249642)
							(end 0.2794 0.1778)
						)
						(arc
							(start 0.2794 -0.1778)
							(mid 0.249642 -0.249642)
							(end 0.1778 -0.2794)
						)
					)
					(width 0)
					(fill yes)
				)
			)
		)
		(pad "2" smd custom
			(at 0 0.4445 180)
			(size 0.1397 0.1397)
			(layers "F.Cu" "F.Mask" "F.Paste")
			(net "U54_A2")
			(options
				(clearance outline)
				(anchor circle)
			)
			(primitives
				(gr_poly
					(pts
						(arc
							(start -0.1778 -0.2794)
							(mid -0.249642 -0.249642)
							(end -0.2794 -0.1778)
						)
						(arc
							(start -0.2794 0.1778)
							(mid -0.249642 0.249642)
							(end -0.1778 0.2794)
						)
						(arc
							(start 0.1778 0.2794)
							(mid 0.249642 0.249642)
							(end 0.2794 0.1778)
						)
						(arc
							(start 0.2794 -0.1778)
							(mid 0.249642 -0.249642)
							(end 0.1778 -0.2794)
						)
					)
					(width 0)
					(fill yes)
				)
			)
		)
	)
)
